FILE_TYPE = MACRO_DRAWING;
SET COLOR_WIRE YELLOW;
SET COLOR_PROP MONO;
SET COLOR_DOT WHITE;
SET COLOR_ARC YELLOW;
SET COLOR_BODY GREEN;
SET COLOR_NOTE MONO;
SET PROP_DISPLAY VALUE;
SET PAGE_NUMBER P238;
FORCEADD OFFPAGE..1
(-2625 2500);
FORCEPROP 2 LAST $XR0 239 
J 0
(-2907 2500);
DISPLAY 0.638298 (-2907 2500);
PAINT MONO (-2907 2500);
FORCEPROP 1 LAST COMMENT_BODY TRUE
J 0
(-2500 2400);
DISPLAY 1.170213 (-2500 2400);
PAINT PEACH (-2500 2400);
DISPLAY INVISIBLE (-2500 2400);
FORCEPROP 1 LAST OFFPAGE TRUE
J 0
(-2300 2375);
PAINT GREEN (-2300 2375);
DISPLAY INVISIBLE (-2300 2375);
FORCEPROP 2 LAST ROOM P1V26_BMC_STBY_VR
J 0
(-3100 2575);
DISPLAY 1.340426 (-3100 2575);
PAINT GREEN (-3100 2575);
DISPLAY INVISIBLE (-3100 2575);
FORCEPROP 2 LAST CDS_LIB mstr_standard
J 0
(-2625 2500);
DISPLAY 1.340426 (-2625 2500);
PAINT ORANGE (-2625 2500);
DISPLAY INVISIBLE (-2625 2500);
FORCEPROP 2 LAST BOM_COST P1V26_BMC_STBY_VR
J 0
(-2900 2550);
PAINT WHITE (-2900 2550);
DISPLAY INVISIBLE (-2900 2550);
FORCEPROP 2 LAST PATH I1
J 0
(-2551 2574);
DISPLAY 1.021277 (-2551 2574);
PAINT ORANGE (-2551 2574);
DISPLAY INVISIBLE (-2551 2574);
FORCEADD GND..1
(1025 1850);
FORCEPROP 3 LASTPIN (1025 1900) SIG_NAME GND\g
J 0
(1035 1910);
DISPLAY 0.659574 (1035 1910);
PAINT MONO (1035 1910);
DISPLAY INVISIBLE (1035 1910);
FORCEPROP 2 LAST P1V5_STBY_IBMC 
J 0
(1050 1975);
PAINT GREEN (1050 1975);
FORCEPROP 2 LAST P1V5_STBY_IBMC_VR 
J 0
(1050 1925);
PAINT GREEN (1050 1925);
FORCEPROP 2 LAST BOM_COST P1V26_BMC_STBY_VR
J 0
(1050 2025);
PAINT WHITE (1050 2025);
DISPLAY INVISIBLE (1050 2025);
FORCEPROP 1 LAST PATH I13
J 0
(1100 1850);
DISPLAY 0.872340 (1100 1850);
PAINT AQUA (1100 1850);
DISPLAY INVISIBLE (1100 1850);
FORCEPROP 1 LAST SIZE 1B
J 0
(1100 1800);
DISPLAY 0.872340 (1100 1800);
PAINT ORANGE (1100 1800);
DISPLAY INVISIBLE (1100 1800);
FORCEPROP 2 LAST CDS_LIB mstr_symbols
J 0
(1025 1850);
PAINT ORANGE (1025 1850);
DISPLAY INVISIBLE (1025 1850);
FORCEPROP 1 LAST VOLTAGE 0.0V
J 0
(980 1807);
DISPLAY 0.340426 (980 1807);
PAINT SKYBLUE (980 1807);
DISPLAY INVISIBLE (980 1807);
FORCEPROP 2 LAST ROOM P1V26_BMC_STBY_VR
J 0
(675 1925);
DISPLAY 0.872340 (675 1925);
PAINT GREEN (675 1925);
DISPLAY INVISIBLE (675 1925);
FORCEPROP 1 LAST BODY_TYPE PLUMBING
J 0
(980 1807);
DISPLAY 0.340426 (980 1807);
PAINT GREEN (980 1807);
DISPLAY INVISIBLE (980 1807);
FORCEPROP 1 LAST HDL_POWER GND
J 0
(1025 2000);
DISPLAY 0.872340 (1025 2000);
PAINT GREEN (1025 2000);
DISPLAY INVISIBLE (1025 2000);
FORCEADD RES..1
R 1
(1025 2100);
FORCEPROP 1 LAST WATTAGE 1/16W
R 1
J 2
(1175 2075);
DISPLAY 0.617021 (1175 2075);
PAINT SKYBLUE (1175 2075);
FORCEPROP 1 LASTPIN (1025 2200) $PN 2
R 1
J 0
(1013 2162);
DISPLAY 0.617021 (1013 2162);
PAINT ORANGE (1013 2162);
FORCEPROP 1 LAST LOCATION R9F8
J 0
(1075 2225);
DISPLAY 0.617021 (1075 2225);
PAINT AQUA (1075 2225);
FORCEPROP 1 LAST MATERIAL CHIP
R 1
J 0
(1175 2100);
DISPLAY 0.617021 (1175 2100);
PAINT SKYBLUE (1175 2100);
FORCEPROP 1 LAST PART_NUMBER G21796-016
R 1
J 0
(1225 1950);
DISPLAY 0.617021 (1225 1950);
PAINT BLUE (1225 1950);
FORCEPROP 2 LAST P1V5_STBY_IBMC 
J 0
(1075 2350);
PAINT GREEN (1075 2350);
FORCEPROP 2 LAST P1V5_STBY_IBMC_VR 
J 0
(1075 2300);
PAINT GREEN (1075 2300);
FORCEPROP 1 LAST VALUE 10.0K
R 1
J 2
(1125 2075);
DISPLAY 0.617021 (1125 2075);
PAINT SKYBLUE (1125 2075);
FORCEPROP 1 LASTPIN (1025 2000) $PN 1
R 1
J 0
(1013 2012);
DISPLAY 0.617021 (1013 2012);
PAINT ORANGE (1013 2012);
FORCEPROP 1 LAST TOLERANCE 1%
R 1
J 0
(1125 2100);
DISPLAY 0.617021 (1125 2100);
PAINT SKYBLUE (1125 2100);
FORCEPROP 1 LAST PACK_TYPE 0402
R 1
J 0
(1275 2000);
DISPLAY 0.617021 (1275 2000);
PAINT SKYBLUE (1275 2000);
FORCEPROP 2 LAST SEC 1
J 0
(1075 2400);
DISPLAY 0.680851 (1075 2400);
PAINT MONO (1075 2400);
DISPLAY INVISIBLE (1075 2400);
FORCEPROP 2 LAST BOM_COST P1V26_BMC_STBY_VR
J 0
(1075 2400);
PAINT WHITE (1075 2400);
DISPLAY INVISIBLE (1075 2400);
FORCEPROP 2 LAST SEC_TYPE 0402
J 0
(1075 2400);
DISPLAY 1.021277 (1075 2400);
PAINT ORANGE (1075 2400);
DISPLAY INVISIBLE (1075 2400);
FORCEPROP 2 LAST CDS_LIB mstr_discrete
J 0
(1025 2100);
PAINT ORANGE (1025 2100);
DISPLAY INVISIBLE (1025 2100);
FORCEPROP 2 LAST CDS_LOCATION R9F8
J 0
(1075 2225);
DISPLAY 0.617021 (1075 2225);
PAINT AQUA (1075 2225);
DISPLAY INVISIBLE (1075 2225);
FORCEPROP 2 LAST ROOM P1V26_BMC_STBY_VR
J 0
(1075 2250);
PAINT GREEN (1075 2250);
DISPLAY INVISIBLE (1075 2250);
FORCEPROP 1 LAST PATH I14
R 1
J 0
(875 2050);
DISPLAY 0.978723 (875 2050);
PAINT WHITE (875 2050);
DISPLAY INVISIBLE (875 2050);
FORCEADD GND..1
(400 2200);
FORCEPROP 3 LASTPIN (400 2250) SIG_NAME GND\g
J 0
(410 2260);
DISPLAY 0.659574 (410 2260);
PAINT MONO (410 2260);
DISPLAY INVISIBLE (410 2260);
FORCEPROP 2 LAST P1V5_STBY_IBMC 
J 0
(425 2325);
PAINT GREEN (425 2325);
FORCEPROP 2 LAST P1V5_STBY_IBMC_VR 
J 0
(425 2275);
PAINT GREEN (425 2275);
FORCEPROP 2 LAST BOM_COST P1V26_BMC_STBY_VR
J 0
(425 2375);
PAINT WHITE (425 2375);
DISPLAY INVISIBLE (425 2375);
FORCEPROP 1 LAST VOLTAGE 0.0V
J 0
(355 2157);
DISPLAY 0.340426 (355 2157);
PAINT SKYBLUE (355 2157);
DISPLAY INVISIBLE (355 2157);
FORCEPROP 2 LAST CDS_LIB mstr_symbols
J 0
(400 2200);
PAINT ORANGE (400 2200);
DISPLAY INVISIBLE (400 2200);
FORCEPROP 1 LAST SIZE 1B
J 0
(475 2150);
DISPLAY 0.872340 (475 2150);
PAINT ORANGE (475 2150);
DISPLAY INVISIBLE (475 2150);
FORCEPROP 1 LAST PATH I15
J 0
(475 2200);
DISPLAY 0.872340 (475 2200);
PAINT AQUA (475 2200);
DISPLAY INVISIBLE (475 2200);
FORCEPROP 2 LAST ROOM P1V26_BMC_STBY_VR
J 0
(50 2275);
DISPLAY 0.872340 (50 2275);
PAINT GREEN (50 2275);
DISPLAY INVISIBLE (50 2275);
FORCEPROP 1 LAST BODY_TYPE PLUMBING
J 0
(355 2157);
DISPLAY 0.340426 (355 2157);
PAINT GREEN (355 2157);
DISPLAY INVISIBLE (355 2157);
FORCEPROP 1 LAST HDL_POWER GND
J 0
(400 2350);
DISPLAY 0.872340 (400 2350);
PAINT GREEN (400 2350);
DISPLAY INVISIBLE (400 2350);
FORCEADD CAP..1
(1250 3050);
FORCEPROP 1 LAST VOLTAGE 50V
J 0
(1300 3050);
DISPLAY 0.829787 (1300 3050);
PAINT SKYBLUE (1300 3050);
FORCEPROP 1 LAST TOLERANCE 10%
J 0
(1300 3000);
DISPLAY 0.617021 (1300 3000);
PAINT SKYBLUE (1300 3000);
FORCEPROP 1 LAST MATERIAL X7R
J 0
(1300 2950);
DISPLAY 0.617021 (1300 2950);
PAINT SKYBLUE (1300 2950);
FORCEPROP 1 LAST VALUE 1000PF
J 0
(1300 3100);
DISPLAY 0.617021 (1300 3100);
PAINT SKYBLUE (1300 3100);
FORCEPROP 1 LAST LOCATION C9F8
J 0
(1300 3150);
DISPLAY 0.617021 (1300 3150);
PAINT AQUA (1300 3150);
FORCEPROP 1 LASTPIN (1250 2950) $PN 2
J 0
(1260 2930);
DISPLAY 0.617021 (1260 2930);
PAINT WHITE (1260 2930);
FORCEPROP 1 LAST PART_NUMBER A36096-046
J 0
(1300 2900);
DISPLAY 0.617021 (1300 2900);
PAINT BLUE (1300 2900);
FORCEPROP 1 LASTPIN (1250 3150) $PN 1
J 0
(1260 3130);
DISPLAY 0.617021 (1260 3130);
PAINT WHITE (1260 3130);
FORCEPROP 1 LAST PACK_TYPE 0402LF
J 0
(1300 2850);
DISPLAY 0.617021 (1300 2850);
PAINT SKYBLUE (1300 2850);
FORCEPROP 2 LAST BOM_COST P1V26_BMC_STBY_VR
J 0
(1310 3190);
DISPLAY 1.617021 (1310 3190);
PAINT WHITE (1310 3190);
DISPLAY INVISIBLE (1310 3190);
FORCEPROP 2 LAST CDS_SEC 1
J 0
(1310 3265);
DISPLAY 1.617021 (1310 3265);
PAINT MONO (1310 3265);
DISPLAY INVISIBLE (1310 3265);
FORCEPROP 2 LAST $SEC 1
J 0
(1310 3265);
DISPLAY 1.617021 (1310 3265);
PAINT MONO (1310 3265);
DISPLAY INVISIBLE (1310 3265);
FORCEPROP 2 LAST CDS_LOCATION C9F8
J 0
(1300 3150);
DISPLAY 0.617021 (1300 3150);
PAINT AQUA (1300 3150);
DISPLAY INVISIBLE (1300 3150);
FORCEPROP 1 LAST PATH I19
J 0
(1300 3200);
DISPLAY 0.978723 (1300 3200);
PAINT WHITE (1300 3200);
DISPLAY INVISIBLE (1300 3200);
FORCEPROP 2 LAST ROOM P1V26_BMC_STBY_VR
J 0
(1310 3190);
DISPLAY 1.617021 (1310 3190);
PAINT GREEN (1310 3190);
DISPLAY INVISIBLE (1310 3190);
FORCEPROP 2 LAST CDS_LIB mstr_discrete
J 0
(1250 3050);
DISPLAY 1.617021 (1250 3050);
PAINT MONO (1250 3050);
DISPLAY INVISIBLE (1250 3050);
FORCEADD GND..1
(1250 2825);
FORCEPROP 3 LASTPIN (1250 2875) SIG_NAME GND\g
J 0
(1260 2885);
DISPLAY 0.659574 (1260 2885);
PAINT MONO (1260 2885);
DISPLAY INVISIBLE (1260 2885);
FORCEPROP 1 LAST SIZE 1B
J 0
(1325 2775);
DISPLAY 1.063830 (1325 2775);
PAINT GREEN (1325 2775);
DISPLAY INVISIBLE (1325 2775);
FORCEPROP 1 LAST PATH I20
J 0
(1325 2825);
DISPLAY 0.872340 (1325 2825);
PAINT AQUA (1325 2825);
DISPLAY INVISIBLE (1325 2825);
FORCEPROP 2 LAST CDS_LIB mstr_symbols
J 0
(1250 2825);
DISPLAY 1.617021 (1250 2825);
PAINT MONO (1250 2825);
DISPLAY INVISIBLE (1250 2825);
FORCEPROP 1 LAST VOLTAGE 0.0V
J 0
(1205 2782);
DISPLAY 0.340426 (1205 2782);
PAINT SKYBLUE (1205 2782);
DISPLAY INVISIBLE (1205 2782);
FORCEPROP 2 LAST BOM_COST P1V26_BMC_STBY_VR
J 0
(935 2915);
DISPLAY 1.617021 (935 2915);
PAINT WHITE (935 2915);
DISPLAY INVISIBLE (935 2915);
FORCEPROP 2 LAST ROOM P1V26_BMC_STBY_VR
J 0
(600 2900);
DISPLAY 1.212766 (600 2900);
PAINT GREEN (600 2900);
DISPLAY INVISIBLE (600 2900);
FORCEPROP 1 LAST BODY_TYPE PLUMBING
J 0
(1205 2782);
DISPLAY 0.340426 (1205 2782);
PAINT GREEN (1205 2782);
DISPLAY INVISIBLE (1205 2782);
FORCEPROP 1 LAST HDL_POWER GND
J 0
(1250 2975);
DISPLAY 1.063830 (1250 2975);
PAINT GREEN (1250 2975);
DISPLAY INVISIBLE (1250 2975);
FORCEADD RES..2
(900 3500);
FORCEPROP 1 LAST PACK_TYPE 0402
J 0
(940 3325);
DISPLAY 0.617021 (940 3325);
PAINT SKYBLUE (940 3325);
FORCEPROP 1 LAST PART_NUMBER G21796-016
J 0
(940 3375);
DISPLAY 0.617021 (940 3375);
PAINT BLUE (940 3375);
FORCEPROP 1 LAST MATERIAL CHIP
J 0
(940 3425);
DISPLAY 0.617021 (940 3425);
PAINT SKYBLUE (940 3425);
FORCEPROP 1 LAST WATTAGE 1/16W
J 0
(940 3475);
DISPLAY 0.617021 (940 3475);
PAINT SKYBLUE (940 3475);
FORCEPROP 1 LAST TOLERANCE 1%
J 0
(945 3525);
DISPLAY 0.617021 (945 3525);
PAINT SKYBLUE (945 3525);
FORCEPROP 1 LAST VALUE 10.0K
J 0
(945 3575);
DISPLAY 0.617021 (945 3575);
PAINT SKYBLUE (945 3575);
FORCEPROP 1 LAST LOCATION R9F13
J 0
(945 3625);
DISPLAY 0.617021 (945 3625);
PAINT AQUA (945 3625);
FORCEPROP 2 LAST P1V5_STBY_IBMC 
J 0
(850 3700);
PAINT GREEN (850 3700);
FORCEPROP 2 LAST P1V5_STBY_IBMC_VR 
J 0
(850 3650);
PAINT GREEN (850 3650);
FORCEPROP 1 LASTPIN (900 3600) $PN 1
J 0
(905 3562);
DISPLAY 0.617021 (905 3562);
PAINT WHITE (905 3562);
FORCEPROP 1 LASTPIN (900 3400) $PN 2
J 0
(905 3410);
DISPLAY 0.617021 (905 3410);
PAINT WHITE (905 3410);
FORCEPROP 1 LAST PATH I21
J 0
(950 3675);
DISPLAY 0.978723 (950 3675);
PAINT WHITE (950 3675);
DISPLAY INVISIBLE (950 3675);
FORCEPROP 2 LAST CDS_LOCATION R9F13
J 0
(945 3625);
DISPLAY 0.617021 (945 3625);
PAINT AQUA (945 3625);
DISPLAY INVISIBLE (945 3625);
FORCEPROP 2 LAST SEC 1
J 0
(850 3750);
DISPLAY 1.106383 (850 3750);
PAINT MONO (850 3750);
DISPLAY INVISIBLE (850 3750);
FORCEPROP 2 LAST SEC_TYPE 0402
J 0
(850 3750);
DISPLAY 1.659574 (850 3750);
PAINT ORANGE (850 3750);
DISPLAY INVISIBLE (850 3750);
FORCEPROP 2 LAST BOM_COST P1V26_BMC_STBY_VR
J 0
(850 3750);
PAINT WHITE (850 3750);
DISPLAY INVISIBLE (850 3750);
FORCEPROP 2 LAST ROOM P1V26_BMC_STBY_VR
J 0
(850 3600);
PAINT GREEN (850 3600);
DISPLAY INVISIBLE (850 3600);
FORCEPROP 2 LAST CDS_LIB mstr_discrete
J 0
(900 3500);
PAINT ORANGE (900 3500);
DISPLAY INVISIBLE (900 3500);
FORCEADD P3V3_STBY..1
(900 3825);
FORCEPROP 3 LASTPIN (900 3775) SIG_NAME P3V3_STBY\g
J 0
(910 3785);
DISPLAY 0.659574 (910 3785);
PAINT MONO (910 3785);
DISPLAY INVISIBLE (910 3785);
FORCEPROP 1 LAST SIZE 1B
J 0
(945 3847);
DISPLAY 0.340426 (945 3847);
PAINT GREEN (945 3847);
DISPLAY INVISIBLE (945 3847);
FORCEPROP 1 LAST VOLTAGE 3.3V
J 0
(855 3782);
DISPLAY 0.340426 (855 3782);
PAINT SKYBLUE (855 3782);
DISPLAY INVISIBLE (855 3782);
FORCEPROP 1 LAST PATH I22
J 0
(945 3827);
DISPLAY 0.340426 (945 3827);
PAINT GREEN (945 3827);
DISPLAY INVISIBLE (945 3827);
FORCEPROP 2 LAST CDS_LIB mstr_symbols
J 0
(900 3825);
PAINT ORANGE (900 3825);
DISPLAY INVISIBLE (900 3825);
FORCEPROP 1 LAST BODY_TYPE PLUMBING
J 0
(855 3782);
DISPLAY 0.340426 (855 3782);
PAINT GREEN (855 3782);
DISPLAY INVISIBLE (855 3782);
FORCEPROP 1 LAST HDL_POWER P3V3_STBY
J 0
(600 3700);
DISPLAY 0.872340 (600 3700);
PAINT ORANGE (600 3700);
DISPLAY INVISIBLE (600 3700);
FORCEADD CAP..1
(1600 2525);
FORCEPROP 1 LAST LOCATION C9E10
J 0
(1650 2625);
DISPLAY 0.617021 (1650 2625);
PAINT AQUA (1650 2625);
FORCEPROP 1 LAST PACK_TYPE 0603
J 0
(1650 2325);
DISPLAY 0.617021 (1650 2325);
PAINT SKYBLUE (1650 2325);
FORCEPROP 1 LASTPIN (1600 2425) $PN 2
J 0
(1610 2405);
DISPLAY 0.617021 (1610 2405);
PAINT WHITE (1610 2405);
FORCEPROP 1 LASTPIN (1600 2625) $PN 1
J 0
(1610 2605);
DISPLAY 0.617021 (1610 2605);
PAINT WHITE (1610 2605);
FORCEPROP 1 LAST MATERIAL X6S
J 0
(1650 2425);
DISPLAY 0.617021 (1650 2425);
PAINT SKYBLUE (1650 2425);
FORCEPROP 1 LAST VALUE 10UF
J 0
(1650 2575);
DISPLAY 0.617021 (1650 2575);
PAINT SKYBLUE (1650 2575);
FORCEPROP 1 LAST PART_NUMBER E15431-002
J 0
(1650 2375);
DISPLAY 0.617021 (1650 2375);
PAINT BLUE (1650 2375);
FORCEPROP 1 LAST VOLTAGE 6.3V
J 0
(1650 2525);
DISPLAY 0.617021 (1650 2525);
PAINT SKYBLUE (1650 2525);
FORCEPROP 1 LAST TOLERANCE 20%
J 0
(1650 2475);
DISPLAY 0.617021 (1650 2475);
PAINT SKYBLUE (1650 2475);
FORCEPROP 2 LAST CDS_LIB mstr_discrete
J 0
(1600 2525);
PAINT ORANGE (1600 2525);
DISPLAY INVISIBLE (1600 2525);
FORCEPROP 2 LAST CDS_LOCATION C9E10
J 0
(1650 2625);
DISPLAY 0.617021 (1650 2625);
PAINT AQUA (1650 2625);
DISPLAY INVISIBLE (1650 2625);
FORCEPROP 1 LAST PATH I23
J 0
(1650 2675);
DISPLAY 0.978723 (1650 2675);
PAINT WHITE (1650 2675);
DISPLAY INVISIBLE (1650 2675);
FORCEPROP 2 LAST BOM_COST P1V26_BMC_STBY_VR
J 0
(1650 2675);
PAINT WHITE (1650 2675);
DISPLAY INVISIBLE (1650 2675);
FORCEPROP 2 LAST SEC 1
J 0
(1650 2725);
DISPLAY 1.106383 (1650 2725);
PAINT MONO (1650 2725);
DISPLAY INVISIBLE (1650 2725);
FORCEPROP 2 LAST ROOM P1V26_BMC_STBY_VR
J 0
(1650 2725);
PAINT GREEN (1650 2725);
DISPLAY INVISIBLE (1650 2725);
FORCEPROP 2 LAST SEC_TYPE 0603
J 0
(1650 2725);
DISPLAY 1.659574 (1650 2725);
PAINT ORANGE (1650 2725);
DISPLAY INVISIBLE (1650 2725);
FORCEADD OFFPAGE..2
(2750 3200);
FORCEPROP 2 LAST $XR0 191 
J 0
(2939 3200);
DISPLAY 0.638298 (2939 3200);
PAINT MONO (2939 3200);
FORCEPROP 2 LAST PATH I25
J 0
(2925 3275);
DISPLAY 1.021277 (2925 3275);
PAINT ORANGE (2925 3275);
DISPLAY INVISIBLE (2925 3275);
FORCEPROP 2 LAST CDS_LIB mstr_standard
J 0
(2750 3200);
PAINT ORANGE (2750 3200);
DISPLAY INVISIBLE (2750 3200);
FORCEPROP 1 LAST OFFPAGE TRUE
J 0
(3075 3075);
DISPLAY 0.872340 (3075 3075);
PAINT GREEN (3075 3075);
DISPLAY INVISIBLE (3075 3075);
FORCEPROP 1 LAST COMMENT_BODY TRUE
J 0
(2705 3105);
DISPLAY 0.872340 (2705 3105);
PAINT GREEN (2705 3105);
DISPLAY INVISIBLE (2705 3105);
FORCEADD GND..1
(2325 2175);
FORCEPROP 3 LASTPIN (2325 2225) SIG_NAME GND\g
J 0
(2335 2235);
DISPLAY 0.659574 (2335 2235);
PAINT MONO (2335 2235);
DISPLAY INVISIBLE (2335 2235);
FORCEPROP 2 LAST P1V5_STBY_IBMC_VR 
J 0
(2350 2250);
PAINT GREEN (2350 2250);
FORCEPROP 2 LAST P1V5_STBY_IBMC 
J 0
(2350 2300);
PAINT GREEN (2350 2300);
FORCEPROP 1 LAST HDL_POWER GND
J 0
(2325 2325);
DISPLAY 0.872340 (2325 2325);
PAINT GREEN (2325 2325);
DISPLAY INVISIBLE (2325 2325);
FORCEPROP 1 LAST BODY_TYPE PLUMBING
J 0
(2280 2132);
DISPLAY 0.340426 (2280 2132);
PAINT GREEN (2280 2132);
DISPLAY INVISIBLE (2280 2132);
FORCEPROP 2 LAST ROOM P1V26_BMC_STBY_VR
J 0
(1975 2250);
DISPLAY 0.872340 (1975 2250);
PAINT GREEN (1975 2250);
DISPLAY INVISIBLE (1975 2250);
FORCEPROP 1 LAST VOLTAGE 0.0V
J 0
(2280 2132);
DISPLAY 0.340426 (2280 2132);
PAINT SKYBLUE (2280 2132);
DISPLAY INVISIBLE (2280 2132);
FORCEPROP 1 LAST SIZE 1B
J 0
(2400 2125);
DISPLAY 0.872340 (2400 2125);
PAINT ORANGE (2400 2125);
DISPLAY INVISIBLE (2400 2125);
FORCEPROP 2 LAST CDS_LIB mstr_symbols
J 0
(2325 2175);
PAINT ORANGE (2325 2175);
DISPLAY INVISIBLE (2325 2175);
FORCEPROP 1 LAST PATH I27
J 0
(2400 2175);
DISPLAY 0.872340 (2400 2175);
PAINT AQUA (2400 2175);
DISPLAY INVISIBLE (2400 2175);
FORCEPROP 2 LAST BOM_COST P1V26_BMC_STBY_VR
J 0
(2350 2350);
PAINT WHITE (2350 2350);
DISPLAY INVISIBLE (2350 2350);
FORCEADD GND..1
(-2000 1775);
FORCEPROP 3 LASTPIN (-2000 1825) SIG_NAME GND\g
J 0
(-1990 1835);
DISPLAY 0.659574 (-1990 1835);
PAINT MONO (-1990 1835);
DISPLAY INVISIBLE (-1990 1835);
FORCEPROP 2 LAST P1V5_STBY_IBMC_VR 
J 0
(-1975 1850);
PAINT GREEN (-1975 1850);
FORCEPROP 2 LAST P1V5_STBY_IBMC 
J 0
(-1975 1900);
PAINT GREEN (-1975 1900);
FORCEPROP 2 LAST BOM_COST P1V26_BMC_STBY_VR
J 0
(-1975 1950);
PAINT WHITE (-1975 1950);
DISPLAY INVISIBLE (-1975 1950);
FORCEPROP 1 LAST PATH I3
J 0
(-1925 1775);
DISPLAY 0.872340 (-1925 1775);
PAINT AQUA (-1925 1775);
DISPLAY INVISIBLE (-1925 1775);
FORCEPROP 2 LAST CDS_LIB mstr_symbols
J 0
(-2000 1775);
PAINT ORANGE (-2000 1775);
DISPLAY INVISIBLE (-2000 1775);
FORCEPROP 1 LAST SIZE 1B
J 0
(-1925 1725);
DISPLAY 0.872340 (-1925 1725);
PAINT ORANGE (-1925 1725);
DISPLAY INVISIBLE (-1925 1725);
FORCEPROP 1 LAST VOLTAGE 0.0V
J 0
(-2045 1732);
DISPLAY 0.340426 (-2045 1732);
PAINT SKYBLUE (-2045 1732);
DISPLAY INVISIBLE (-2045 1732);
FORCEPROP 2 LAST ROOM P1V26_BMC_STBY_VR
J 0
(-2350 1850);
DISPLAY 0.872340 (-2350 1850);
PAINT GREEN (-2350 1850);
DISPLAY INVISIBLE (-2350 1850);
FORCEPROP 1 LAST BODY_TYPE PLUMBING
J 0
(-2045 1732);
DISPLAY 0.340426 (-2045 1732);
PAINT GREEN (-2045 1732);
DISPLAY INVISIBLE (-2045 1732);
FORCEPROP 1 LAST HDL_POWER GND
J 0
(-2000 1925);
DISPLAY 0.872340 (-2000 1925);
PAINT GREEN (-2000 1925);
DISPLAY INVISIBLE (-2000 1925);
FORCEADD CAP..1
(2325 2525);
FORCEPROP 1 LASTPIN (2325 2425) $PN 2
J 0
(2335 2405);
DISPLAY 0.617021 (2335 2405);
PAINT WHITE (2335 2405);
FORCEPROP 1 LAST PART_NUMBER C95333-002
J 0
(2375 2375);
DISPLAY 0.617021 (2375 2375);
PAINT BLUE (2375 2375);
FORCEPROP 1 LAST PACK_TYPE 0805LF
J 0
(2375 2325);
DISPLAY 0.617021 (2375 2325);
PAINT SKYBLUE (2375 2325);
FORCEPROP 1 LAST VOLTAGE 4V
J 0
(2375 2525);
DISPLAY 0.617021 (2375 2525);
PAINT SKYBLUE (2375 2525);
FORCEPROP 1 LASTPIN (2325 2625) $PN 1
J 0
(2335 2605);
DISPLAY 0.617021 (2335 2605);
PAINT WHITE (2335 2605);
FORCEPROP 1 LAST VALUE 22UF
J 0
(2375 2575);
DISPLAY 0.617021 (2375 2575);
PAINT SKYBLUE (2375 2575);
FORCEPROP 1 LAST LOCATION C9F4
J 0
(2375 2625);
DISPLAY 0.617021 (2375 2625);
PAINT AQUA (2375 2625);
FORCEPROP 1 LAST MATERIAL X6S
J 0
(2375 2425);
DISPLAY 0.617021 (2375 2425);
PAINT SKYBLUE (2375 2425);
FORCEPROP 1 LAST TOLERANCE 20%
J 0
(2375 2475);
DISPLAY 0.617021 (2375 2475);
PAINT SKYBLUE (2375 2475);
FORCEPROP 2 LAST ROOM P1V26_BMC_STBY_VR
J 0
(2375 2725);
PAINT GREEN (2375 2725);
DISPLAY INVISIBLE (2375 2725);
FORCEPROP 1 LAST PATH I30
J 0
(2375 2675);
DISPLAY 0.978723 (2375 2675);
PAINT WHITE (2375 2675);
DISPLAY INVISIBLE (2375 2675);
FORCEPROP 2 LAST CDS_LOCATION C9F4
J 0
(2375 2625);
DISPLAY 0.617021 (2375 2625);
PAINT AQUA (2375 2625);
DISPLAY INVISIBLE (2375 2625);
FORCEPROP 2 LAST SEC 1
J 0
(2375 2725);
DISPLAY 1.106383 (2375 2725);
PAINT MONO (2375 2725);
DISPLAY INVISIBLE (2375 2725);
FORCEPROP 2 LAST SEC_TYPE 0805LF
J 0
(2375 2725);
DISPLAY 1.659574 (2375 2725);
PAINT ORANGE (2375 2725);
DISPLAY INVISIBLE (2375 2725);
FORCEPROP 2 LAST BOM_COST P1V26_BMC_STBY_VR
J 0
(2375 2675);
PAINT WHITE (2375 2675);
DISPLAY INVISIBLE (2375 2675);
FORCEPROP 2 LAST CDS_LIB mstr_discrete
J 0
(2325 2525);
PAINT ORANGE (2325 2525);
DISPLAY INVISIBLE (2325 2525);
FORCEADD CAP..1
(-1275 2150);
FORCEPROP 1 LAST TOLERANCE 10%
J 0
(-1225 2100);
DISPLAY 0.617021 (-1225 2100);
PAINT SKYBLUE (-1225 2100);
FORCEPROP 1 LAST MATERIAL X6S
J 0
(-1225 2050);
DISPLAY 0.617021 (-1225 2050);
PAINT SKYBLUE (-1225 2050);
FORCEPROP 1 LASTPIN (-1275 2050) $PN 2
J 0
(-1265 2030);
DISPLAY 0.617021 (-1265 2030);
PAINT ORANGE (-1265 2030);
FORCEPROP 1 LAST PART_NUMBER D97712-011
J 0
(-1225 2000);
DISPLAY 0.617021 (-1225 2000);
PAINT BLUE (-1225 2000);
FORCEPROP 1 LAST PACK_TYPE 0402
J 0
(-1225 1950);
DISPLAY 0.617021 (-1225 1950);
PAINT SKYBLUE (-1225 1950);
FORCEPROP 1 LASTPIN (-1275 2250) $PN 1
J 0
(-1265 2230);
DISPLAY 0.617021 (-1265 2230);
PAINT ORANGE (-1265 2230);
FORCEPROP 1 LAST VOLTAGE 16V
J 0
(-1225 2150);
DISPLAY 0.617021 (-1225 2150);
PAINT SKYBLUE (-1225 2150);
FORCEPROP 1 LAST LOCATION C9E11
J 0
(-1225 2250);
DISPLAY 0.617021 (-1225 2250);
PAINT AQUA (-1225 2250);
FORCEPROP 1 LAST VALUE 1.0UF
J 0
(-1225 2200);
DISPLAY 0.617021 (-1225 2200);
PAINT SKYBLUE (-1225 2200);
FORCEPROP 2 LAST SEC_TYPE 0402
J 0
(-1225 2350);
DISPLAY 1.021277 (-1225 2350);
PAINT ORANGE (-1225 2350);
DISPLAY INVISIBLE (-1225 2350);
FORCEPROP 2 LAST SEC 1
J 0
(-1225 2350);
DISPLAY 0.680851 (-1225 2350);
PAINT MONO (-1225 2350);
DISPLAY INVISIBLE (-1225 2350);
FORCEPROP 1 LAST PATH I39
J 0
(-1225 2300);
DISPLAY 0.978723 (-1225 2300);
PAINT WHITE (-1225 2300);
DISPLAY INVISIBLE (-1225 2300);
FORCEPROP 2 LAST CDS_LIB mstr_discrete
J 0
(-1275 2150);
PAINT MONO (-1275 2150);
DISPLAY INVISIBLE (-1275 2150);
FORCEPROP 2 LAST CDS_LOCATION C9E11
J 0
(-1225 2250);
DISPLAY 0.617021 (-1225 2250);
PAINT AQUA (-1225 2250);
DISPLAY INVISIBLE (-1225 2250);
FORCEADD GND..1
(-1275 1750);
FORCEPROP 3 LASTPIN (-1275 1800) SIG_NAME GND\g
J 0
(-1265 1810);
DISPLAY 0.659574 (-1265 1810);
PAINT MONO (-1265 1810);
DISPLAY INVISIBLE (-1265 1810);
FORCEPROP 1 LAST VOLTAGE 0.0V
J 0
(-1320 1707);
DISPLAY 0.340426 (-1320 1707);
PAINT SKYBLUE (-1320 1707);
DISPLAY INVISIBLE (-1320 1707);
FORCEPROP 2 LAST CDS_LIB mstr_symbols
J 0
(-1275 1750);
PAINT ORANGE (-1275 1750);
DISPLAY INVISIBLE (-1275 1750);
FORCEPROP 1 LAST SIZE 1B
J 0
(-1200 1700);
DISPLAY 0.872340 (-1200 1700);
PAINT AQUA (-1200 1700);
DISPLAY INVISIBLE (-1200 1700);
FORCEPROP 1 LAST PATH I4
J 0
(-1200 1750);
DISPLAY 0.872340 (-1200 1750);
PAINT AQUA (-1200 1750);
DISPLAY INVISIBLE (-1200 1750);
FORCEPROP 1 LAST BODY_TYPE PLUMBING
J 0
(-1320 1707);
DISPLAY 0.340426 (-1320 1707);
PAINT GREEN (-1320 1707);
DISPLAY INVISIBLE (-1320 1707);
FORCEPROP 1 LAST HDL_POWER GND
J 0
(-1275 1900);
DISPLAY 0.872340 (-1275 1900);
PAINT GREEN (-1275 1900);
DISPLAY INVISIBLE (-1275 1900);
FORCEADD RT9059..1
(-175 2700);
FORCEPROP 2 LASTPIN (-675 2500) $PN 6
J 2
(-685 2510);
DISPLAY 0.617021 (-685 2510);
PAINT ORANGE (-685 2510);
FORCEPROP 2 LASTPIN (325 2400) $PN 11
J 0
(335 2410);
DISPLAY 0.617021 (335 2410);
PAINT ORANGE (335 2410);
FORCEPROP 2 LASTPIN (325 2500) $PN 4
J 0
(335 2510);
DISPLAY 0.617021 (335 2510);
PAINT ORANGE (335 2510);
FORCEPROP 1 LAST MATERIAL IC
J 0
(-625 3100);
DISPLAY 0.617021 (-625 3100);
PAINT SKYBLUE (-625 3100);
FORCEPROP 2 LASTPIN (325 2700) $PN 2
J 0
(335 2710);
DISPLAY 0.617021 (335 2710);
PAINT ORANGE (335 2710);
FORCEPROP 2 LASTPIN (325 2650) $PN 1
J 0
(335 2660);
DISPLAY 0.617021 (335 2660);
PAINT ORANGE (335 2660);
FORCEPROP 2 LASTPIN (325 2900) $PN 5
J 0
(335 2910);
DISPLAY 0.617021 (335 2910);
PAINT ORANGE (335 2910);
FORCEPROP 1 LAST LOCATION EU9F1
J 0
(-625 3150);
DISPLAY 0.617021 (-625 3150);
PAINT AQUA (-625 3150);
FORCEPROP 2 LASTPIN (-675 2900) $PN 10
J 2
(-685 2910);
DISPLAY 0.617021 (-685 2910);
PAINT ORANGE (-685 2910);
FORCEPROP 2 LASTPIN (-675 2700) $PN 8
J 2
(-685 2710);
DISPLAY 0.617021 (-685 2710);
PAINT ORANGE (-685 2710);
FORCEPROP 2 LASTPIN (-675 2750) $PN 9
J 2
(-685 2760);
DISPLAY 0.617021 (-685 2760);
PAINT ORANGE (-685 2760);
FORCEPROP 2 LASTPIN (325 2750) $PN 3
J 0
(335 2760);
DISPLAY 0.617021 (335 2760);
PAINT ORANGE (335 2760);
FORCEPROP 2 LASTPIN (-675 2650) $PN 7
J 2
(-685 2660);
DISPLAY 0.617021 (-685 2660);
PAINT ORANGE (-685 2660);
FORCEPROP 1 LAST PART_NUMBER H65765-001
J 0
(-625 2300);
DISPLAY 0.617021 (-625 2300);
PAINT BLUE (-625 2300);
FORCEPROP 1 LAST PACK_TYPE DFN
J 0
(-625 3200);
PAINT SKYBLUE (-625 3200);
DISPLAY INVISIBLE (-625 3200);
FORCEPROP 2 LAST SEC_TYPE DFN
J 0
(-625 3200);
DISPLAY 1.021277 (-625 3200);
PAINT ORANGE (-625 3200);
DISPLAY INVISIBLE (-625 3200);
FORCEPROP 2 LAST SEC 1
J 0
(-625 3200);
DISPLAY 0.680851 (-625 3200);
PAINT MONO (-625 3200);
DISPLAY INVISIBLE (-625 3200);
FORCEPROP 2 LAST CDS_LOCATION EU9F1
J 0
(-625 3150);
DISPLAY 0.617021 (-625 3150);
PAINT AQUA (-625 3150);
DISPLAY INVISIBLE (-625 3150);
FORCEPROP 1 LAST PATH I40
J 0
(-125 3100);
PAINT GREEN (-125 3100);
DISPLAY INVISIBLE (-125 3100);
FORCEPROP 0 LAST ROOM P1V26_BMC_STBY_VR
J 0
(-625 3250);
DISPLAY 1.021277 (-625 3250);
PAINT ORANGE (-625 3250);
DISPLAY INVISIBLE (-625 3250);
FORCEPROP 2 LAST CDS_LIB mstr_vreg
J 0
(-175 2700);
PAINT MONO (-175 2700);
DISPLAY INVISIBLE (-175 2700);
FORCEADD RES..1
(1850 3200);
FORCEPROP 1 LAST WATTAGE 1/16W
J 2
(1825 3050);
DISPLAY 0.617021 (1825 3050);
PAINT SKYBLUE (1825 3050);
FORCEPROP 1 LAST VALUE 22.1
J 2
(1825 3100);
DISPLAY 0.617021 (1825 3100);
PAINT SKYBLUE (1825 3100);
FORCEPROP 1 LAST TOLERANCE 1.0%
J 0
(1850 3100);
DISPLAY 0.617021 (1850 3100);
PAINT SKYBLUE (1850 3100);
FORCEPROP 1 LASTPIN (1950 3200) $PN 2
J 0
(1912 3212);
DISPLAY 0.617021 (1912 3212);
PAINT ORANGE (1912 3212);
FORCEPROP 1 LAST LOCATION R9F11
J 0
(1800 3250);
DISPLAY 0.617021 (1800 3250);
PAINT AQUA (1800 3250);
FORCEPROP 1 LAST PART_NUMBER G21796-250
J 0
(1800 3300);
DISPLAY 0.617021 (1800 3300);
PAINT BLUE (1800 3300);
FORCEPROP 1 LASTPIN (1750 3200) $PN 1
J 0
(1762 3212);
DISPLAY 0.617021 (1762 3212);
PAINT ORANGE (1762 3212);
FORCEPROP 1 LAST MATERIAL CHIP
J 0
(1850 3050);
DISPLAY 0.617021 (1850 3050);
PAINT SKYBLUE (1850 3050);
FORCEPROP 1 LAST PACK_TYPE 0402
J 0
(2100 3050);
DISPLAY 0.617021 (2100 3050);
PAINT SKYBLUE (2100 3050);
FORCEPROP 1 LAST PATH I41
J 0
(1800 3350);
DISPLAY 0.978723 (1800 3350);
PAINT WHITE (1800 3350);
DISPLAY INVISIBLE (1800 3350);
FORCEPROP 0 LAST ROOM P1V26_BMC_STBY_VR
J 0
(1800 3400);
DISPLAY 1.021277 (1800 3400);
PAINT ORANGE (1800 3400);
DISPLAY INVISIBLE (1800 3400);
FORCEPROP 2 LAST SEC 1
J 0
(1800 3400);
DISPLAY 0.680851 (1800 3400);
PAINT MONO (1800 3400);
DISPLAY INVISIBLE (1800 3400);
FORCEPROP 2 LAST SEC_TYPE 0402
J 0
(1800 3400);
DISPLAY 1.021277 (1800 3400);
PAINT ORANGE (1800 3400);
DISPLAY INVISIBLE (1800 3400);
FORCEPROP 2 LAST CDS_LOCATION R9F11
J 0
(1800 3250);
DISPLAY 0.617021 (1800 3250);
PAINT AQUA (1800 3250);
DISPLAY INVISIBLE (1800 3250);
FORCEPROP 2 LAST CDS_LIB mstr_discrete
J 0
(1850 3200);
PAINT MONO (1850 3200);
DISPLAY INVISIBLE (1850 3200);
FORCEADD P3V3_STBY..1
(-1275 3075);
FORCEPROP 3 LASTPIN (-1275 3025) SIG_NAME P3V3_STBY\g
J 0
(-1265 3035);
DISPLAY 0.659574 (-1265 3035);
PAINT MONO (-1265 3035);
DISPLAY INVISIBLE (-1265 3035);
FORCEPROP 1 LAST SIZE 1B
J 0
(-1230 3097);
DISPLAY 0.340426 (-1230 3097);
PAINT GREEN (-1230 3097);
DISPLAY INVISIBLE (-1230 3097);
FORCEPROP 2 LAST CDS_LIB mstr_symbols
J 0
(-1275 3075);
PAINT ORANGE (-1275 3075);
DISPLAY INVISIBLE (-1275 3075);
FORCEPROP 1 LAST PATH I42
J 0
(-1230 3077);
DISPLAY 0.340426 (-1230 3077);
PAINT GREEN (-1230 3077);
DISPLAY INVISIBLE (-1230 3077);
FORCEPROP 1 LAST VOLTAGE 3.3V
J 0
(-1320 3032);
DISPLAY 0.340426 (-1320 3032);
PAINT SKYBLUE (-1320 3032);
DISPLAY INVISIBLE (-1320 3032);
FORCEPROP 1 LAST BODY_TYPE PLUMBING
J 0
(-1320 3032);
DISPLAY 0.340426 (-1320 3032);
PAINT GREEN (-1320 3032);
DISPLAY INVISIBLE (-1320 3032);
FORCEPROP 1 LAST HDL_POWER P3V3_STBY
J 0
(-1575 2950);
DISPLAY 0.872340 (-1575 2950);
PAINT ORANGE (-1575 2950);
DISPLAY INVISIBLE (-1575 2950);
FORCEADD W_VCC_CIRCLE..1
(2325 2825);
FORCEPROP 3 LASTPIN (2325 2825) SIG_NAME P1V15_AUX_BMC\g
J 0
(2335 2835);
DISPLAY 0.659574 (2335 2835);
PAINT MONO (2335 2835);
DISPLAY INVISIBLE (2335 2835);
FORCEPROP 1 LAST HDL_POWER P1V15_AUX_BMC
J 1
(2346 2900);
DISPLAY 0.872340 (2346 2900);
PAINT ORANGE (2346 2900);
FORCEPROP 1 LAST CDS_LMAN_SYM_OUTLINE -100,100,100,-100
J 0
(2325 2825);
DISPLAY 0.468085 (2325 2825);
PAINT GREEN (2325 2825);
DISPLAY INVISIBLE (2325 2825);
FORCEPROP 1 LAST PATH I43
J 0
(2325 2825);
DISPLAY 0.617021 (2325 2825);
PAINT GREEN (2325 2825);
DISPLAY INVISIBLE (2325 2825);
FORCEPROP 2 LAST CDS_LIB w_power
J 0
(2325 2825);
PAINT MONO (2325 2825);
DISPLAY INVISIBLE (2325 2825);
FORCEPROP 1 LAST BODY_TYPE PLUMBING
J 0
(2337 2819);
DISPLAY 0.340426 (2337 2819);
PAINT GREEN (2337 2819);
DISPLAY INVISIBLE (2337 2819);
FORCEADD P3V3_STBY..1
(-2500 3550);
FORCEPROP 3 LASTPIN (-2500 3500) SIG_NAME P3V3_STBY\g
J 0
(-2490 3510);
DISPLAY 0.659574 (-2490 3510);
PAINT MONO (-2490 3510);
DISPLAY INVISIBLE (-2490 3510);
FORCEPROP 1 LAST HDL_POWER P3V3_STBY
J 0
(-2800 3425);
DISPLAY 0.872340 (-2800 3425);
PAINT ORANGE (-2800 3425);
DISPLAY INVISIBLE (-2800 3425);
FORCEPROP 1 LAST BODY_TYPE PLUMBING
J 0
(-2545 3507);
DISPLAY 0.340426 (-2545 3507);
PAINT GREEN (-2545 3507);
DISPLAY INVISIBLE (-2545 3507);
FORCEPROP 1 LAST SIZE 1B
J 0
(-2455 3572);
DISPLAY 0.340426 (-2455 3572);
PAINT GREEN (-2455 3572);
DISPLAY INVISIBLE (-2455 3572);
FORCEPROP 1 LAST VOLTAGE 3.3V
J 0
(-2545 3507);
DISPLAY 0.340426 (-2545 3507);
PAINT SKYBLUE (-2545 3507);
DISPLAY INVISIBLE (-2545 3507);
FORCEPROP 1 LAST PATH I44
J 0
(-2455 3552);
DISPLAY 0.340426 (-2455 3552);
PAINT GREEN (-2455 3552);
DISPLAY INVISIBLE (-2455 3552);
FORCEPROP 2 LAST CDS_LIB mstr_symbols
J 0
(-2500 3550);
PAINT MONO (-2500 3550);
DISPLAY INVISIBLE (-2500 3550);
FORCEADD 4K42R2F-GP..1
(1025 2475);
FORCEPROP 2 LAST TOLERANCE 1%
J 0
(1050 2425);
DISPLAY 0.638298 (1050 2425);
PAINT GREEN (1050 2425);
FORCEPROP 2 LAST PACK_SIZE 0402
J 0
(1050 2325);
DISPLAY 0.638298 (1050 2325);
PAINT GREEN (1050 2325);
FORCEPROP 2 LAST RATED 1/16W
J 0
(1050 2375);
DISPLAY 0.638298 (1050 2375);
PAINT GREEN (1050 2375);
FORCEPROP 1 LAST LOCATION R9F6
J 0
(1045 2580);
DISPLAY 0.617021 (1045 2580);
PAINT GREEN (1045 2580);
FORCEPROP 1 LAST VALUE 4K42R2F-GP
J 0
(1045 2525);
DISPLAY 0.617021 (1045 2525);
PAINT GREEN (1045 2525);
FORCEPROP 2 LAST ATTRIBUTE 4.42KOHM
J 0
(1050 2475);
DISPLAY 0.638298 (1050 2475);
PAINT GREEN (1050 2475);
FORCEPROP 1 LAST PACK_TYPE SMD-RG
J 0
(1025 2475);
DISPLAY 0.617021 (1025 2475);
PAINT GREEN (1025 2475);
DISPLAY INVISIBLE (1025 2475);
FORCEPROP 1 LAST PART_NUMBER 64.44215.6DL
J 0
(1025 2475);
DISPLAY 0.617021 (1025 2475);
PAINT GREEN (1025 2475);
DISPLAY INVISIBLE (1025 2475);
FORCEPROP 2 LAST CDS_LIB w_hdl
J 0
(1025 2475);
PAINT MONO (1025 2475);
DISPLAY INVISIBLE (1025 2475);
FORCEPROP 1 LAST PATH I45
J 0
(1025 2475);
DISPLAY 0.617021 (1025 2475);
PAINT GREEN (1025 2475);
DISPLAY INVISIBLE (1025 2475);
FORCEPROP 1 LAST CDS_LMAN_SYM_OUTLINE -50,75,50,-75
J 0
(1025 2475);
DISPLAY 0.468085 (1025 2475);
PAINT GREEN (1025 2475);
DISPLAY INVISIBLE (1025 2475);
FORCEADD CAP..1
(-2050 3050);
FORCEPROP 1 LASTPIN (-2050 2950) $PN 2
J 0
(-2040 2930);
DISPLAY 0.617021 (-2040 2930);
PAINT WHITE (-2040 2930);
FORCEPROP 1 LAST PACK_TYPE 0603
J 0
(-2000 2850);
DISPLAY 0.617021 (-2000 2850);
PAINT SKYBLUE (-2000 2850);
FORCEPROP 1 LAST PART_NUMBER E15431-002
J 0
(-2000 2900);
DISPLAY 0.617021 (-2000 2900);
PAINT BLUE (-2000 2900);
FORCEPROP 1 LAST MATERIAL X6S
J 0
(-2000 2950);
DISPLAY 0.617021 (-2000 2950);
PAINT SKYBLUE (-2000 2950);
FORCEPROP 1 LASTPIN (-2050 3150) $PN 1
J 0
(-2040 3130);
DISPLAY 0.617021 (-2040 3130);
PAINT WHITE (-2040 3130);
FORCEPROP 1 LAST VALUE 10UF
J 0
(-2000 3100);
DISPLAY 0.617021 (-2000 3100);
PAINT SKYBLUE (-2000 3100);
FORCEPROP 0 LAST POP NOPOP
J 0
(-2000 2800);
DISPLAY 0.638298 (-2000 2800);
PAINT RED (-2000 2800);
FORCEPROP 1 LAST TOLERANCE 20%
J 0
(-2000 3000);
DISPLAY 0.617021 (-2000 3000);
PAINT SKYBLUE (-2000 3000);
FORCEPROP 1 LAST VOLTAGE 6.3V
J 0
(-2000 3050);
DISPLAY 0.617021 (-2000 3050);
PAINT SKYBLUE (-2000 3050);
FORCEPROP 1 LAST LOCATION C9W14
J 0
(-2000 3150);
DISPLAY 0.617021 (-2000 3150);
PAINT AQUA (-2000 3150);
FORCEPROP 1 LAST PATH I46
J 0
(-2000 3200);
DISPLAY 0.978723 (-2000 3200);
PAINT WHITE (-2000 3200);
DISPLAY INVISIBLE (-2000 3200);
FORCEPROP 2 LAST SEC 1
J 0
(-2000 3250);
DISPLAY 1.106383 (-2000 3250);
PAINT MONO (-2000 3250);
DISPLAY INVISIBLE (-2000 3250);
FORCEPROP 2 LAST SEC_TYPE 0603
J 0
(-2000 3250);
DISPLAY 1.659574 (-2000 3250);
PAINT ORANGE (-2000 3250);
DISPLAY INVISIBLE (-2000 3250);
FORCEPROP 2 LAST ROOM P1V26_BMC_STBY_VR
J 0
(-2000 3200);
DISPLAY 0.723404 (-2000 3200);
PAINT GREEN (-2000 3200);
DISPLAY INVISIBLE (-2000 3200);
FORCEPROP 2 LAST BOM_COST P1V26_BMC_STBY_VR
J 0
(-2175 3200);
PAINT WHITE (-2175 3200);
DISPLAY INVISIBLE (-2175 3200);
FORCEPROP 2 LAST CDS_LIB mstr_discrete
J 0
(-2050 3050);
PAINT ORANGE (-2050 3050);
DISPLAY INVISIBLE (-2050 3050);
FORCEPROP 2 LAST CDS_LOCATION C9W14
J 0
(-2000 3150);
DISPLAY 0.617021 (-2000 3150);
PAINT AQUA (-2000 3150);
DISPLAY INVISIBLE (-2000 3150);
FORCEADD GND..1
(-2050 2775);
FORCEPROP 3 LASTPIN (-2050 2825) SIG_NAME GND\g
J 0
(-2040 2835);
DISPLAY 0.659574 (-2040 2835);
PAINT MONO (-2040 2835);
DISPLAY INVISIBLE (-2040 2835);
FORCEPROP 1 LAST PATH I47
J 0
(-1975 2775);
DISPLAY 0.872340 (-1975 2775);
PAINT AQUA (-1975 2775);
DISPLAY INVISIBLE (-1975 2775);
FORCEPROP 2 LAST CDS_LIB mstr_symbols
J 0
(-2050 2775);
PAINT ORANGE (-2050 2775);
DISPLAY INVISIBLE (-2050 2775);
FORCEPROP 1 LAST SIZE 1B
J 0
(-1975 2725);
DISPLAY 0.872340 (-1975 2725);
PAINT AQUA (-1975 2725);
DISPLAY INVISIBLE (-1975 2725);
FORCEPROP 1 LAST VOLTAGE 0.0V
J 0
(-2095 2732);
DISPLAY 0.340426 (-2095 2732);
PAINT SKYBLUE (-2095 2732);
DISPLAY INVISIBLE (-2095 2732);
FORCEPROP 1 LAST BODY_TYPE PLUMBING
J 0
(-2095 2732);
DISPLAY 0.340426 (-2095 2732);
PAINT GREEN (-2095 2732);
DISPLAY INVISIBLE (-2095 2732);
FORCEPROP 1 LAST HDL_POWER GND
J 0
(-2050 2925);
DISPLAY 0.872340 (-2050 2925);
PAINT GREEN (-2050 2925);
DISPLAY INVISIBLE (-2050 2925);
FORCEADD CAP..1
R 2
(-2000 2175);
FORCEPROP 1 LAST PART_NUMBER A36096-046
J 2
(-2050 2025);
DISPLAY 0.617021 (-2050 2025);
PAINT BLUE (-2050 2025);
FORCEPROP 1 LAST MATERIAL EMPTY
J 2
(-2050 2075);
DISPLAY 0.617021 (-2050 2075);
PAINT RED (-2050 2075);
FORCEPROP 1 LAST PACK_TYPE 0402LF
J 2
(-2175 2125);
DISPLAY 0.617021 (-2175 2125);
PAINT SKYBLUE (-2175 2125);
FORCEPROP 1 LAST VALUE 1000PF
J 2
(-2150 2200);
DISPLAY 0.617021 (-2150 2200);
PAINT SKYBLUE (-2150 2200);
FORCEPROP 1 LASTPIN (-2000 2275) $PN 1
J 2
(-2010 2255);
DISPLAY 0.617021 (-2010 2255);
PAINT WHITE (-2010 2255);
FORCEPROP 1 LASTPIN (-2000 2075) $PN 2
J 2
(-2010 2055);
DISPLAY 0.617021 (-2010 2055);
PAINT WHITE (-2010 2055);
FORCEPROP 1 LAST TOLERANCE 10%
J 2
(-2050 2125);
DISPLAY 0.617021 (-2050 2125);
PAINT SKYBLUE (-2050 2125);
FORCEPROP 1 LAST LOCATION C9F9
J 2
(-2175 2250);
DISPLAY 0.617021 (-2175 2250);
PAINT AQUA (-2175 2250);
FORCEPROP 1 LAST VOLTAGE 50V
J 2
(-2050 2175);
DISPLAY 0.617021 (-2050 2175);
PAINT SKYBLUE (-2050 2175);
FORCEPROP 2 LAST CDS_SEC 1
J 0
(-2040 2385);
DISPLAY 1.617021 (-2040 2385);
PAINT MONO (-2040 2385);
DISPLAY INVISIBLE (-2040 2385);
FORCEPROP 2 LAST $SEC 1
J 0
(-2040 2385);
DISPLAY 1.617021 (-2040 2385);
PAINT MONO (-2040 2385);
DISPLAY INVISIBLE (-2040 2385);
FORCEPROP 2 LAST CDS_LIB mstr_discrete
J 0
(-2000 2175);
DISPLAY 1.617021 (-2000 2175);
PAINT MONO (-2000 2175);
DISPLAY INVISIBLE (-2000 2175);
FORCEPROP 1 LAST PATH I5
J 2
(-2050 2325);
DISPLAY 0.978723 (-2050 2325);
PAINT WHITE (-2050 2325);
DISPLAY INVISIBLE (-2050 2325);
FORCEPROP 2 LAST BOM_COST P1V26_BMC_STBY_VR
J 0
(-2065 2285);
DISPLAY 1.617021 (-2065 2285);
PAINT WHITE (-2065 2285);
DISPLAY INVISIBLE (-2065 2285);
FORCEPROP 2 LAST ROOM P1V26_BMC_STBY_VR
J 2
(-2050 2300);
DISPLAY 1.212766 (-2050 2300);
PAINT GREEN (-2050 2300);
DISPLAY INVISIBLE (-2050 2300);
FORCEPROP 2 LAST CDS_LOCATION C9F9
J 2
(-2175 2250);
DISPLAY 0.617021 (-2175 2250);
PAINT AQUA (-2175 2250);
DISPLAY INVISIBLE (-2175 2250);
FORCEADD CAP_A..1
(1950 2550);
FORCEPROP 1 LASTPIN (1950 2450) $PN 2
J 0
(1960 2430);
DISPLAY 0.617021 (1960 2430);
PAINT GREEN (1960 2430);
FORCEPROP 1 LASTPIN (1950 2650) $PN 1
J 0
(1960 2630);
DISPLAY 0.617021 (1960 2630);
PAINT GREEN (1960 2630);
FORCEPROP 1 LAST VOLTAGE 4V
J 0
(2000 2550);
DISPLAY 0.617021 (2000 2550);
PAINT SKYBLUE (2000 2550);
FORCEPROP 1 LAST VALUE 22.0UF
J 0
(2000 2600);
DISPLAY 0.617021 (2000 2600);
PAINT SKYBLUE (2000 2600);
FORCEPROP 1 LAST LOCATION C9W16
J 0
(2000 2650);
DISPLAY 0.617021 (2000 2650);
PAINT AQUA (2000 2650);
FORCEPROP 1 LAST TOLERANCE 20%
J 0
(2000 2500);
DISPLAY 0.617021 (2000 2500);
PAINT SKYBLUE (2000 2500);
FORCEPROP 1 LAST MATERIAL X6S
J 0
(2000 2450);
DISPLAY 0.617021 (2000 2450);
PAINT SKYBLUE (2000 2450);
FORCEPROP 1 LAST PACK_TYPE 0603V
J 0
(2000 2350);
DISPLAY 0.617021 (2000 2350);
PAINT SKYBLUE (2000 2350);
FORCEPROP 1 LAST PART_NUMBER E15431-004
J 0
(2000 2400);
DISPLAY 0.617021 (2000 2400);
PAINT BLUE (2000 2400);
FORCEPROP 0 LAST POP NOPOP
J 0
(2000 2300);
DISPLAY 0.638298 (2000 2300);
PAINT RED (2000 2300);
FORCEPROP 1 LAST PATH I50
J 0
(2000 2700);
DISPLAY 0.978723 (2000 2700);
PAINT WHITE (2000 2700);
DISPLAY INVISIBLE (2000 2700);
FORCEPROP 2 LAST ROOM PVCCIN_CPU0_DECAP_VR
J 0
(2000 2700);
DISPLAY 1.021277 (2000 2700);
PAINT ORANGE (2000 2700);
DISPLAY INVISIBLE (2000 2700);
FORCEPROP 2 LAST $SEC 1
J 0
(2000 2750);
PAINT MONO (2000 2750);
DISPLAY INVISIBLE (2000 2750);
FORCEPROP 2 LAST CDS_SEC 1
J 0
(2000 2750);
PAINT MONO (2000 2750);
DISPLAY INVISIBLE (2000 2750);
FORCEPROP 2 LAST CDS_LIB dev_discrete
J 0
(1950 2550);
PAINT ORANGE (1950 2550);
DISPLAY INVISIBLE (1950 2550);
FORCEPROP 2 LAST BOM_COST PROC_SOCKET
J 0
(2000 2750);
DISPLAY 1.021277 (2000 2750);
PAINT ORANGE (2000 2750);
DISPLAY INVISIBLE (2000 2750);
FORCEPROP 2 LAST CDS_LOCATION C9W16
J 0
(2000 2650);
DISPLAY 0.617021 (2000 2650);
PAINT AQUA (2000 2650);
DISPLAY INVISIBLE (2000 2650);
FORCEADD GND..1
(-2500 2775);
FORCEPROP 3 LASTPIN (-2500 2825) SIG_NAME GND\g
J 0
(-2490 2835);
DISPLAY 0.659574 (-2490 2835);
PAINT MONO (-2490 2835);
DISPLAY INVISIBLE (-2490 2835);
FORCEPROP 1 LAST HDL_POWER GND
J 0
(-2500 2925);
DISPLAY 0.872340 (-2500 2925);
PAINT GREEN (-2500 2925);
DISPLAY INVISIBLE (-2500 2925);
FORCEPROP 1 LAST BODY_TYPE PLUMBING
J 0
(-2545 2732);
DISPLAY 0.340426 (-2545 2732);
PAINT GREEN (-2545 2732);
DISPLAY INVISIBLE (-2545 2732);
FORCEPROP 1 LAST PATH I6
J 0
(-2425 2775);
DISPLAY 0.872340 (-2425 2775);
PAINT AQUA (-2425 2775);
DISPLAY INVISIBLE (-2425 2775);
FORCEPROP 1 LAST VOLTAGE 0.0V
J 0
(-2545 2732);
DISPLAY 0.340426 (-2545 2732);
PAINT SKYBLUE (-2545 2732);
DISPLAY INVISIBLE (-2545 2732);
FORCEPROP 1 LAST SIZE 1B
J 0
(-2425 2725);
DISPLAY 0.872340 (-2425 2725);
PAINT AQUA (-2425 2725);
DISPLAY INVISIBLE (-2425 2725);
FORCEPROP 2 LAST CDS_LIB mstr_symbols
J 0
(-2500 2775);
PAINT ORANGE (-2500 2775);
DISPLAY INVISIBLE (-2500 2775);
FORCEADD CAP..1
(-2500 3025);
FORCEPROP 1 LASTPIN (-2500 2925) $PN 2
J 0
(-2490 2905);
DISPLAY 0.617021 (-2490 2905);
PAINT WHITE (-2490 2905);
FORCEPROP 1 LASTPIN (-2500 3125) $PN 1
J 0
(-2490 3105);
DISPLAY 0.617021 (-2490 3105);
PAINT WHITE (-2490 3105);
FORCEPROP 1 LAST MATERIAL X6S
J 0
(-2450 2925);
DISPLAY 0.617021 (-2450 2925);
PAINT SKYBLUE (-2450 2925);
FORCEPROP 1 LAST TOLERANCE 20%
J 0
(-2450 2975);
DISPLAY 0.617021 (-2450 2975);
PAINT SKYBLUE (-2450 2975);
FORCEPROP 1 LAST VOLTAGE 6.3V
J 0
(-2450 3025);
DISPLAY 0.617021 (-2450 3025);
PAINT SKYBLUE (-2450 3025);
FORCEPROP 1 LAST VALUE 10UF
J 0
(-2450 3075);
DISPLAY 0.617021 (-2450 3075);
PAINT SKYBLUE (-2450 3075);
FORCEPROP 1 LAST LOCATION C9F3
J 0
(-2450 3125);
DISPLAY 0.617021 (-2450 3125);
PAINT AQUA (-2450 3125);
FORCEPROP 1 LAST PACK_TYPE 0603
J 0
(-2450 2825);
DISPLAY 0.617021 (-2450 2825);
PAINT SKYBLUE (-2450 2825);
FORCEPROP 1 LAST PART_NUMBER E15431-002
J 0
(-2450 2875);
DISPLAY 0.617021 (-2450 2875);
PAINT BLUE (-2450 2875);
FORCEPROP 2 LAST CDS_LIB mstr_discrete
J 0
(-2500 3025);
PAINT ORANGE (-2500 3025);
DISPLAY INVISIBLE (-2500 3025);
FORCEPROP 2 LAST BOM_COST P1V26_BMC_STBY_VR
J 0
(-2625 3175);
PAINT WHITE (-2625 3175);
DISPLAY INVISIBLE (-2625 3175);
FORCEPROP 2 LAST CDS_LOCATION C9F3
J 0
(-2450 3125);
DISPLAY 0.617021 (-2450 3125);
PAINT AQUA (-2450 3125);
DISPLAY INVISIBLE (-2450 3125);
FORCEPROP 1 LAST PATH I7
J 0
(-2450 3175);
DISPLAY 0.978723 (-2450 3175);
PAINT WHITE (-2450 3175);
DISPLAY INVISIBLE (-2450 3175);
FORCEPROP 2 LAST ROOM P1V26_BMC_STBY_VR
J 0
(-2450 3175);
DISPLAY 0.723404 (-2450 3175);
PAINT GREEN (-2450 3175);
DISPLAY INVISIBLE (-2450 3175);
FORCEPROP 2 LAST SEC_TYPE 0603
J 0
(-2450 3225);
DISPLAY 1.659574 (-2450 3225);
PAINT ORANGE (-2450 3225);
DISPLAY INVISIBLE (-2450 3225);
FORCEPROP 2 LAST SEC 1
J 0
(-2450 3225);
DISPLAY 1.106383 (-2450 3225);
PAINT MONO (-2450 3225);
DISPLAY INVISIBLE (-2450 3225);
FORCEADD INTEL_CORP_BPAGE..1
(4250 200);
FORCEPROP 1 LAST CDS_CON_LAST_MODIFIED Fri Jun 16 17:49:25 2017
J 0
(2825 525);
PAINT ORANGE (2825 525);
DISPLAY INVISIBLE (2825 525);
FORCEPROP 1 LAST CUSTOM_TXT_CDS <CURRENT_DESIGN_SHEET> OF <TOTAL_DESIGN_SHEETS>
J 0
(3750 225);
PAINT ORANGE (3750 225);
FORCEPROP 1 LAST CUSTOM_TXT_CDS <CON_LAST_MODIFIED>
J 0
(250 300);
PAINT ORANGE (250 300);
FORCEPROP 2 LAST CUSTOM_TXT_CDS <XR_PAGE_TITLE>
J 0
(-3640 5450);
DISPLAY 0.638298 (-3640 5450);
PAINT PINK (-3640 5450);
DISPLAY INVISIBLE (-3640 5450);
FORCEPROP 1 LAST SCH_TITLE P1V15 BMC STBY VR
J 0
(-3700 250);
DISPLAY 1.212766 (-3700 250);
PAINT ORANGE (-3700 250);
FORCEPROP 2 LAST CDS_LIB mstr_symbols
J 0
(4250 200);
PAINT MONO (4250 200);
DISPLAY INVISIBLE (4250 200);
FORCEPROP 2 LAST PAGE_BORDER TRUE
J 0
(-3640 5450);
DISPLAY 0.638298 (-3640 5450);
PAINT PINK (-3640 5450);
DISPLAY INVISIBLE (-3640 5450);
FORCEPROP 1 LAST COMMENT_BODY TRUE
J 0
(4262 212);
DISPLAY 0.468085 (4262 212);
PAINT GREEN (4262 212);
DISPLAY INVISIBLE (4262 212);
FORCEPROP 2 LAST CDS_XR_PAGE_TITLE CR-238 : @BASEBOARD_FAB2_LIB.BASEBOARD_FAB2(SCH_1):PAGE238
J 0
(-3640 5450);
DISPLAY 0.638298 (-3640 5450);
PAINT PINK (-3640 5450);
DISPLAY INVISIBLE (-3640 5450);
FORCEADD CAD_NOTE..1
(-2975 3125);
FORCEPROP 0 LAST L1 MUST PLACE
J 0
(-3125 3025);
DISPLAY 0.744681 (-3125 3025);
PAINT WHITE (-3125 3025);
FORCEPROP 0 LAST L2 NEXT TO INPUT PIN
J 0
(-3125 2975);
DISPLAY 0.744681 (-3125 2975);
PAINT WHITE (-3125 2975);
FORCEPROP 1 LAST COMMENT_BODY TRUE
J 0
(-2950 3225);
DISPLAY 2.212766 (-2950 3225);
PAINT PEACH (-2950 3225);
DISPLAY INVISIBLE (-2950 3225);
FORCEPROP 2 LAST ROOM P1V26_BMC_STBY_VR
J 0
(-3125 3075);
DISPLAY 1.659574 (-3125 3075);
PAINT GREEN (-3125 3075);
DISPLAY INVISIBLE (-3125 3075);
FORCEPROP 2 LAST CDS_LIB mstr_symbols
J 0
(-2975 3125);
DISPLAY 1.617021 (-2975 3125);
PAINT WHITE (-2975 3125);
DISPLAY INVISIBLE (-2975 3125);
FORCEADD DESIGN_NOTE..1
(2925 3800);
FORCEPROP 2 LAST CDS_LIB mstr_symbols
J 0
(2925 3800);
PAINT ORANGE (2925 3800);
DISPLAY INVISIBLE (2925 3800);
FORCEPROP 1 LAST COMMENT_BODY TRUE
J 0
(2950 3900);
DISPLAY 1.361702 (2950 3900);
PAINT WHITE (2950 3900);
DISPLAY INVISIBLE (2950 3900);
FORCEADD DNS..2
(-1995 2170);
PAINT RED (-1995 2170);
FORCEPROP 2 LAST CDS_LIB mstr_misc
J 0
(-1995 2170);
PAINT ORANGE (-1995 2170);
DISPLAY INVISIBLE (-1995 2170);
FORCEPROP 1 LAST COMMENT_BODY TRUE
R 1
J 0
(-1920 1945);
DISPLAY 0.872340 (-1920 1945);
PAINT GREEN (-1920 1945);
DISPLAY INVISIBLE (-1920 1945);
WIRE 16 -1 (1025 2000)(1025 1900);
WIRE 16 -1 (400 2250)(400 2400);
WIRE 16 -1 (325 2400)(400 2400);
WIRE 16 -1 (1250 2875)(1250 2950);
WIRE 16 -1 (900 3600)(900 3775);
WIRE 16 -1 (2325 2225)(2325 2250);
WIRE 16 -1 (1950 2250)(2325 2250);
WIRE 16 -1 (2325 2425)(2325 2250);
WIRE 16 -1 (1600 2250)(1950 2250);
WIRE 16 -1 (1950 2450)(1950 2250);
WIRE 16 -1 (1600 2250)(1600 2425);
WIRE 16 -1 (-2000 2075)(-2000 1825);
WIRE 16 -1 (-1275 1800)(-1275 2050);
WIRE 16 -1 (-1275 3025)(-1275 2900);
WIRE 16 -1 (-1275 2900)(-675 2900);
WIRE 16 -1 (-1275 2250)(-1275 2900);
WIRE 16 -1 (2325 2750)(2325 2825);
WIRE 16 -1 (2325 2750)(1950 2750);
FORCEPROP 0 LAST VOLTAGE 1.5
J 0
(2200 2800);
PAINT SKYBLUE (2200 2800);
DISPLAY INVISIBLE (2200 2800);
WIRE 16 -1 (2325 2625)(2325 2750);
WIRE 16 -1 (1600 2750)(1950 2750);
WIRE 16 -1 (1950 2750)(1950 2650);
WIRE 16 -1 (1025 2750)(1600 2750);
WIRE 16 -1 (1600 2750)(1600 2625);
WIRE 16 -1 (550 2750)(1025 2750);
WIRE 16 -1 (1025 2600)(1025 2750);
WIRE 16 -1 (550 2750)(550 2700);
WIRE 16 -1 (325 2750)(550 2750);
WIRE 16 -1 (550 2650)(550 2700);
WIRE 16 -1 (550 2700)(325 2700);
WIRE 16 -1 (325 2650)(550 2650);
WIRE 16 -1 (-2500 3500)(-2500 3200);
FORCEPROP 0 LAST VOLTAGE 3.3 V
J 0
(-2500 3375);
PAINT SKYBLUE (-2500 3375);
DISPLAY INVISIBLE (-2500 3375);
WIRE 16 -1 (-2500 3200)(-2050 3200);
WIRE 16 -1 (-2500 3125)(-2500 3200);
WIRE 16 -1 (-2050 3200)(-1050 3200);
WIRE 16 -1 (-2050 3200)(-2050 3150);
WIRE 16 -1 (-1050 3200)(-1050 2750);
WIRE 16 -1 (-1050 2700)(-1050 2750);
WIRE 16 -1 (-1050 2750)(-675 2750);
WIRE 16 -1 (-1050 2700)(-1050 2650);
WIRE 16 -1 (-1050 2700)(-675 2700);
WIRE 16 -1 (-1050 2650)(-675 2650);
WIRE 16 -1 (-2050 2950)(-2050 2825);
WIRE 16 -1 (-2500 2925)(-2500 2825);
WIRE 3 682 (-2100 3250)(-2100 2750);
WIRE 3 682 (-1500 3250)(-2100 3250);
WIRE 3 682 (-2100 2750)(-1500 2750);
WIRE 3 682 (-1500 2750)(-1500 3250);
WIRE 3 2175 (1550 3000)(3325 3000);
WIRE 3 2175 (3325 3000)(3325 2700);
WIRE 3 2175 (1550 3000)(1550 2700);
WIRE 3 2175 (1550 2700)(3325 2700);
WIRE 3 682 (1900 2800)(1900 2200);
WIRE 3 682 (2250 2800)(1900 2800);
WIRE 3 682 (1900 2200)(2250 2200);
WIRE 3 682 (2250 2200)(2250 2800);
WIRE 3 2175 (950 2650)(950 2300);
WIRE 3 2175 (950 2300)(1300 2300);
WIRE 3 2175 (950 2650)(1300 2650);
WIRE 3 2175 (1300 2650)(1300 2300);
WIRE 16 -1 (1025 2200)(1025 2250);
WIRE 16 -1 (1025 2250)(1025 2350);
WIRE 16 -1 (875 2250)(1025 2250);
WIRE 16 -1 (875 2500)(875 2250);
WIRE 16 -1 (325 2500)(875 2500);
FORCEPROP 2 LAST SIG_NAME VR_P1V15_BMC_STBY_FB
J 0
(390 2510);
DISPLAY 0.617021 (390 2510);
PAINT ORANGE (390 2510);
FORCEPROP 2 LASTPROP $XRERR UNIQUE?
J 0
(150 2510);
DISPLAY 0.638298 (150 2510);
PAINT MONO (150 2510);
DISPLAY INVISIBLE (150 2510);
WIRE 16 -1 (1250 3150)(1250 3200);
WIRE 16 -1 (1250 3200)(1750 3200);
WIRE 16 -1 (900 3200)(900 3400);
WIRE 16 -1 (900 3200)(1250 3200);
FORCEPROP 2 LAST SIG_NAME PWRGD_P1V15_BMC_STBY_R
J 0
(966 3210);
DISPLAY 0.617021 (966 3210);
PAINT ORANGE (966 3210);
FORCEPROP 2 LASTPROP $XRERR UNIQUE?
J 0
(726 3210);
DISPLAY 0.638298 (726 3210);
PAINT MONO (726 3210);
DISPLAY INVISIBLE (726 3210);
WIRE 16 -1 (700 3200)(900 3200);
WIRE 16 -1 (700 2900)(700 3200);
WIRE 16 -1 (325 2900)(700 2900);
WIRE 16 -1 (-2575 2500)(-2000 2500);
FORCEPROP 2 LAST SIG_NAME PWRGD_P1V2_BMC_STBY
J 0
(-2560 2510);
DISPLAY 0.617021 (-2560 2510);
PAINT ORANGE (-2560 2510);
WIRE 16 -1 (-2000 2275)(-2000 2500);
WIRE 16 -1 (-675 2500)(-2000 2500);
WIRE 16 -1 (1950 3200)(2700 3200);
FORCEPROP 2 LAST SIG_NAME PWRGD_P1V15_BMC_STBY
J 0
(2066 3210);
DISPLAY 0.617021 (2066 3210);
PAINT ORANGE (2066 3210);
WIRE 16 2175 (-3200 2750)(-3200 3250);
WIRE 16 2175 (-2150 2750)(-3200 2750);
WIRE 16 2175 (-3200 3250)(-2150 3250);
WIRE 16 2175 (-2150 3250)(-2150 2750);
DOT 1 (-2050 3200);
DOT 1 (-2500 3200);
DOT 1 (550 2700);
DOT 1 (900 3200);
DOT 1 (-2000 2500);
DOT 1 (550 2750);
DOT 1 (1025 2750);
DOT 1 (1250 3200);
DOT 1 (1025 2250);
DOT 1 (-1050 2700);
DOT 1 (-1050 2750);
DOT 1 (1600 2750);
DOT 1 (-1275 2900);
DOT 1 (1950 2750);
DOT 1 (1950 2250);
DOT 1 (2325 2250);
DOT 1 (2325 2750);
FORCENOTE
TP FAB3 RESERVE CAP 1031
(1725 2800) 0;
DISPLAY LEFT (1725 2800);
DISPLAY 0.638298 (1725 2800);
PAINT RED (1725 2800);
FORCENOTE
VOUT=1.15V
(2725 3650) 0;
DISPLAY LEFT (2725 3650);
DISPLAY 1.021277 (2725 3650);
PAINT PURPLE (2725 3650);
FORCENOTE
IOUT=700MA
(2725 3575) 0;
DISPLAY LEFT (2725 3575);
DISPLAY 1.021277 (2725 3575);
PAINT PURPLE (2725 3575);
FORCENOTE
TP FAB3 RESERVE CAP 1031
(-2100 2700) 0;
DISPLAY LEFT (-2100 2700);
DISPLAY 0.638298 (-2100 2700);
PAINT RED (-2100 2700);
FORCENOTE
TP FAB1 CHANGE POWER RAIL FOR BMC 1120
(2625 2600) 0;
DISPLAY LEFT (2625 2600);
DISPLAY 0.851064 (2625 2600);
PAINT RED (2625 2600);
FORCENOTE
TP FAB1 CHANGE R9F6 FOR 1.15V POWER RAIL 1123
(1350 1950) 0;
DISPLAY LEFT (1350 1950);
DISPLAY 0.851064 (1350 1950);
PAINT RED (1350 1950);
QUIT
